# T6G (Grand Teton) — schematic netlist excerpt (pin names and nets, part order shuffled) for the footprints in the layout excerpt that follows; sources: Cadence DE-HDL packaged netlist, KiCad conversion of 04192023_DAF0TMB3IC0_F0TG_MB_C_brd_V02_OCP.brd

C6050  Q_CAP  0.1UF 25V 10% X7R  pkg 0402  page 177 : A = P3V3_AUX ; B = GND
R245  Q_RES  0 5% CHIP  pkg 0402LF  page 82 : A = IRQ_SMI_ACTIVE_N ; B = IRQ_SMI_ACTIVE_N_R

(kicad_pcb
	(version 20260206)
	(generator "pcbnew")
	(generator_version "10.0")
	(general
		(thickness 1.6)
		(legacy_teardrops no)
	)
	(paper "A4")
	(title_block
		(title "04192023_DAF0TMB3IC0_F0TG_MB_C_brd_V02_OCP.brd")
		(comment 1 "Grand Teton / footprints 5363-5364 of 8354")
	)
	(layers
		(0 "F.Cu" signal "TOP")
		(4 "In1.Cu" signal "GND")
		(6 "In2.Cu" signal "IN1")
		(8 "In3.Cu" signal "GND1")
		(10 "In4.Cu" signal "IN2")
		(12 "In5.Cu" signal "GND2")
		(14 "In6.Cu" signal "IN3")
		(16 "In7.Cu" signal "GND3")
		(18 "In8.Cu" signal "VCC")
		(20 "In9.Cu" signal "VCC1")
		(22 "In10.Cu" signal "GND4")
		(24 "In11.Cu" signal "IN4")
		(26 "In12.Cu" signal "GND5")
		(28 "In13.Cu" signal "IN5")
		(30 "In14.Cu" signal "GND6")
		(32 "In15.Cu" signal "IN6")
		(34 "In16.Cu" signal "GND7")
		(2 "B.Cu" signal "BOTTOM")
		(9 "F.Adhes" user "F.Adhesive")
		(11 "B.Adhes" user "B.Adhesive")
		(13 "F.Paste" user "Package Geometry/Pastemask Top")
		(15 "B.Paste" user "Package Geometry/Pastemask Bottom")
		(5 "F.SilkS" user "Ref Des/Silkscreen Top")
		(7 "B.SilkS" user "Ref Des/Silkscreen Bottom")
		(1 "F.Mask" user "Board Geometry/Soldermask Top")
		(3 "B.Mask" user "Board Geometry/Soldermask Bottom")
		(17 "Dwgs.User" user "User.Drawings")
		(19 "Cmts.User" user "User.Comments")
		(21 "Eco1.User" user "User.Eco1")
		(23 "Eco2.User" user "User.Eco2")
		(25 "Edge.Cuts" user "Board Geometry/Outline")
		(27 "Margin" user)
		(31 "F.CrtYd" user "Package Geometry/Place Bound Top")
		(29 "B.CrtYd" user "Package Geometry/Place Bound Bottom")
		(35 "F.Fab" user "Ref Des/Assembly Top")
		(33 "B.Fab" user "Ref Des/Assembly Bottom")
	)
	(footprint ""
		(layer "B.Cu")
		(at 131.849114 -33.199578 -90)
		(property "Reference" "C6050"
			(at 0 0 90)
			(layer "B.SilkS")
			(hide yes)
			(effects
				(font
					(size 1.27 1.27)
				)
				(justify mirror)
			)
		)
		(property "Value" ""
			(at 0 0 90)
			(layer "B.Fab")
			(effects
				(font
					(size 1.27 1.27)
				)
				(justify mirror)
			)
		)
		(duplicate_pad_numbers_are_jumpers no)
		(fp_line
			(start -0.7874 0.4064)
			(end 0.7874 0.4064)
			(stroke
				(width 0.1524)
				(type default)
			)
			(layer "B.SilkS")
		)
		(fp_line
			(start 0.7874 0.4064)
			(end 0.7874 -0.4064)
			(stroke
				(width 0.1524)
				(type default)
			)
			(layer "B.SilkS")
		)
		(fp_line
			(start -0.7874 -0.4064)
			(end -0.7874 0.4064)
			(stroke
				(width 0.1524)
				(type default)
			)
			(layer "B.SilkS")
		)
		(fp_line
			(start 0.7874 -0.4064)
			(end -0.7874 -0.4064)
			(stroke
				(width 0.1524)
				(type default)
			)
			(layer "B.SilkS")
		)
		(fp_line
			(start -0.67945 0.3048)
			(end -0.120396 0.3048)
			(stroke
				(width 0.1)
				(type default)
			)
			(layer "B.Fab")
		)
		(fp_line
			(start -0.120396 0.3048)
			(end -0.120396 0.2794)
			(stroke
				(width 0.1)
				(type default)
			)
			(layer "B.Fab")
		)
		(fp_line
			(start 0.12065 0.3048)
			(end 0.67945 0.3048)
			(stroke
				(width 0.1)
				(type default)
			)
			(layer "B.Fab")
		)
		(fp_line
			(start 0.67945 0.3048)
			(end 0.67945 -0.305054)
			(stroke
				(width 0.1)
				(type default)
			)
			(layer "B.Fab")
		)
		(fp_line
			(start -0.120396 0.2794)
			(end 0.12065 0.2794)
			(stroke
				(width 0.1)
				(type default)
			)
			(layer "B.Fab")
		)
		(fp_line
			(start 0.12065 0.2794)
			(end 0.12065 0.3048)
			(stroke
				(width 0.1)
				(type default)
			)
			(layer "B.Fab")
		)
		(fp_line
			(start -0.12065 -0.2794)
			(end -0.12065 -0.3048)
			(stroke
				(width 0.1)
				(type default)
			)
			(layer "B.Fab")
		)
		(fp_line
			(start 0.12065 -0.2794)
			(end -0.12065 -0.2794)
			(stroke
				(width 0.1)
				(type default)
			)
			(layer "B.Fab")
		)
		(fp_line
			(start -0.67945 -0.3048)
			(end -0.67945 0.3048)
			(stroke
				(width 0.1)
				(type default)
			)
			(layer "B.Fab")
		)
		(fp_line
			(start -0.12065 -0.3048)
			(end -0.67945 -0.3048)
			(stroke
				(width 0.1)
				(type default)
			)
			(layer "B.Fab")
		)
		(fp_line
			(start 0.12065 -0.305054)
			(end 0.12065 -0.2794)
			(stroke
				(width 0.1)
				(type default)
			)
			(layer "B.Fab")
		)
		(fp_line
			(start 0.67945 -0.305054)
			(end 0.12065 -0.305054)
			(stroke
				(width 0.1)
				(type default)
			)
			(layer "B.Fab")
		)
		(pad "1" smd circle
			(at 0.40005 0 90)
			(size 0 0)
			(layers "B.Cu" "B.Mask" "B.Paste")
			(net "P3V3_AUX")
		)
		(pad "2" smd circle
			(at -0.40005 0 90)
			(size 0 0)
			(layers "B.Cu" "B.Mask" "B.Paste")
			(net "GND")
		)
	)
	(footprint ""
		(layer "B.Cu")
		(at 184.658 -96.738948)
		(property "Reference" "R245"
			(at 0 0 0)
			(layer "B.SilkS")
			(hide yes)
			(effects
				(font
					(size 1.27 1.27)
				)
				(justify mirror)
			)
		)
		(property "Value" ""
			(at 0 0 0)
			(layer "B.Fab")
			(effects
				(font
					(size 1.27 1.27)
				)
				(justify mirror)
			)
		)
		(duplicate_pad_numbers_are_jumpers no)
		(fp_line
			(start -0.7874 -0.4064)
			(end -0.7874 0.4064)
			(stroke
				(width 0.1524)
				(type default)
			)
			(layer "B.SilkS")
		)
		(fp_line
			(start -0.7874 0.4064)
			(end 0.7874 0.4064)
			(stroke
				(width 0.1524)
				(type default)
			)
			(layer "B.SilkS")
		)
		(fp_line
			(start 0.7874 -0.4064)
			(end -0.7874 -0.4064)
			(stroke
				(width 0.1524)
				(type default)
			)
			(layer "B.SilkS")
		)
		(fp_line
			(start 0.7874 0.4064)
			(end 0.7874 -0.4064)
			(stroke
				(width 0.1524)
				(type default)
			)
			(layer "B.SilkS")
		)
		(fp_line
			(start -0.67945 -0.3048)
			(end -0.67945 0.3048)
			(stroke
				(width 0.1)
				(type default)
			)
			(layer "B.Fab")
		)
		(fp_line
			(start -0.67945 0.3048)
			(end -0.120396 0.3048)
			(stroke
				(width 0.1)
				(type default)
			)
			(layer "B.Fab")
		)
		(fp_line
			(start -0.12065 -0.3048)
			(end -0.67945 -0.3048)
			(stroke
				(width 0.1)
				(type default)
			)
			(layer "B.Fab")
		)
		(fp_line
			(start -0.12065 -0.2794)
			(end -0.12065 -0.3048)
			(stroke
				(width 0.1)
				(type default)
			)
			(layer "B.Fab")
		)
		(fp_line
			(start -0.120396 0.2794)
			(end 0.12065 0.2794)
			(stroke
				(width 0.1)
				(type default)
			)
			(layer "B.Fab")
		)
		(fp_line
			(start -0.120396 0.3048)
			(end -0.120396 0.2794)
			(stroke
				(width 0.1)
				(type default)
			)
			(layer "B.Fab")
		)
		(fp_line
			(start 0.12065 -0.305054)
			(end 0.12065 -0.2794)
			(stroke
				(width 0.1)
				(type default)
			)
			(layer "B.Fab")
		)
		(fp_line
			(start 0.12065 -0.2794)
			(end -0.12065 -0.2794)
			(stroke
				(width 0.1)
				(type default)
			)
			(layer "B.Fab")
		)
		(fp_line
			(start 0.12065 0.2794)
			(end 0.12065 0.3048)
			(stroke
				(width 0.1)
				(type default)
			)
			(layer "B.Fab")
		)
		(fp_line
			(start 0.12065 0.3048)
			(end 0.67945 0.3048)
			(stroke
				(width 0.1)
				(type default)
			)
			(layer "B.Fab")
		)
		(fp_line
			(start 0.67945 -0.305054)
			(end 0.12065 -0.305054)
			(stroke
				(width 0.1)
				(type default)
			)
			(layer "B.Fab")
		)
		(fp_line
			(start 0.67945 0.3048)
			(end 0.67945 -0.305054)
			(stroke
				(width 0.1)
				(type default)
			)
			(layer "B.Fab")
		)
		(pad "1" smd circle
			(at 0.40005 0 180)
			(size 0 0)
			(layers "B.Cu" "B.Mask" "B.Paste")
			(net "IRQ_SMI_ACTIVE_N")
		)
		(pad "2" smd circle
			(at -0.40005 0 180)
			(size 0 0)
			(layers "B.Cu" "B.Mask" "B.Paste")
			(net "IRQ_SMI_ACTIVE_N_R")
		)
	)
)
